(kicad_pcb
	(version 20260206)
	(generator "pcbnew")
	(generator_version "10.0")
	(general
		(thickness 1.6)
		(legacy_teardrops no)
	)
	(paper "A4")
	(title_block
		(title "Wiwynn_Tioga_Pass_MB.brd")
		(comment 1 "Tioga Pass / footprints 1849-1855 of 4770")
	)
	(layers
		(0 "F.Cu" signal "TOP")
		(4 "In1.Cu" signal "L2GND")
		(6 "In2.Cu" signal "L3")
		(8 "In3.Cu" signal "L4GND")
		(10 "In4.Cu" signal "L5")
		(12 "In5.Cu" signal "L6GND")
		(14 "In6.Cu" signal "L7VCC")
		(16 "In7.Cu" signal "L8VCC")
		(18 "In8.Cu" signal "L9GND")
		(20 "In9.Cu" signal "L10")
		(22 "In10.Cu" signal "L11GND")
		(24 "In11.Cu" signal "L12")
		(26 "In12.Cu" signal "L13GND")
		(2 "B.Cu" signal "BOTTOM")
		(9 "F.Adhes" user "F.Adhesive")
		(11 "B.Adhes" user "B.Adhesive")
		(13 "F.Paste" user "Package Geometry/Pastemask Top")
		(15 "B.Paste" user "Package Geometry/Pastemask Bottom")
		(5 "F.SilkS" user "Ref Des/Silkscreen Top")
		(7 "B.SilkS" user "Ref Des/Silkscreen Bottom")
		(1 "F.Mask" user "Board Geometry/Soldermask Top")
		(3 "B.Mask" user "Board Geometry/Soldermask Bottom")
		(17 "Dwgs.User" user "User.Drawings")
		(19 "Cmts.User" user "User.Comments")
		(21 "Eco1.User" user "User.Eco1")
		(23 "Eco2.User" user "User.Eco2")
		(25 "Edge.Cuts" user "Board Geometry/Outline")
		(27 "Margin" user)
		(31 "F.CrtYd" user "Package Geometry/Place Bound Top")
		(29 "B.CrtYd" user "Package Geometry/Place Bound Bottom")
		(35 "F.Fab" user "Ref Des/Assembly Top")
		(33 "B.Fab" user "Ref Des/Assembly Bottom")
	)
	(footprint ""
		(layer "F.Cu")
		(at 414.5788 -112.2426 90)
		(property "Reference" "R2M4"
			(at 0 0 90)
			(layer "F.SilkS")
			(hide yes)
			(effects
				(font
					(size 1.27 1.27)
				)
			)
		)
		(property "Value" ""
			(at 0 0 90)
			(layer "F.Fab")
			(effects
				(font
					(size 1.27 1.27)
				)
			)
		)
		(duplicate_pad_numbers_are_jumpers no)
		(fp_poly
			(pts
				(xy -0.2794 -0.1016) (xy 0.2794 -0.1016) (xy 0.2794 0.9906) (xy -0.2794 0.9906)
			)
			(stroke
				(width 0)
				(type default)
			)
			(fill no)
			(layer "F.CrtYd")
		)
		(fp_line
			(start 0.2794 -0.1016)
			(end -0.2794 -0.1016)
			(stroke
				(width 0.1)
				(type default)
			)
			(layer "F.Fab")
		)
		(fp_line
			(start -0.2794 -0.1016)
			(end -0.2794 0.9906)
			(stroke
				(width 0.1)
				(type default)
			)
			(layer "F.Fab")
		)
		(fp_line
			(start 0.2794 0.9906)
			(end 0.2794 -0.1016)
			(stroke
				(width 0.1)
				(type default)
			)
			(layer "F.Fab")
		)
		(fp_line
			(start -0.2794 0.9906)
			(end 0.2794 0.9906)
			(stroke
				(width 0.1)
				(type default)
			)
			(layer "F.Fab")
		)
		(pad "1" smd rect
			(at 0 0 90)
			(size 0.508 0.508)
			(layers "F.Cu" "F.Mask" "F.Paste")
			(net "P3V3_STBY")
		)
		(pad "2" smd rect
			(at 0 0.889 90)
			(size 0.508 0.508)
			(layers "F.Cu" "F.Mask" "F.Paste")
			(net "IRQ_HSC_FAULT_N")
		)
		(zone
			(layer "F.Cu")
			(hatch none 0.5)
			(connect_pads
				(clearance 0)
			)
			(min_thickness 0.25)
			(keepout
				(tracks allowed)
				(vias not_allowed)
				(pads allowed)
				(copperpour not_allowed)
				(footprints allowed)
			)
			(placement
				(enabled no)
				(sheetname "")
			)
			(fill
				(thermal_gap 0.5)
				(thermal_bridge_width 0.5)
				(island_removal_mode 0)
			)
			(polygon
				(pts
					(xy 414.8328 -111.9886) (xy 414.8328 -112.4966) (xy 415.2138 -112.4966) (xy 415.2138 -111.9886)
				)
			)
		)
		(zone
			(layer "F.Cu")
			(hatch none 0.5)
			(connect_pads
				(clearance 0)
			)
			(min_thickness 0.25)
			(keepout
				(tracks not_allowed)
				(vias allowed)
				(pads allowed)
				(copperpour not_allowed)
				(footprints allowed)
			)
			(placement
				(enabled no)
				(sheetname "")
			)
			(fill
				(thermal_gap 0.5)
				(thermal_bridge_width 0.5)
				(island_removal_mode 0)
			)
			(polygon
				(pts
					(xy 415.2138 -111.9886) (xy 415.2138 -112.4966) (xy 414.8328 -112.4966) (xy 414.8328 -111.9886)
				)
			)
		)
	)
	(footprint ""
		(layer "F.Cu")
		(at 173.9265 -68.834 90)
		(property "Reference" "C4D38"
			(at 0 0 90)
			(layer "F.SilkS")
			(hide yes)
			(effects
				(font
					(size 1.27 1.27)
				)
			)
		)
		(property "Value" ""
			(at 0 0 90)
			(layer "F.Fab")
			(effects
				(font
					(size 1.27 1.27)
				)
			)
		)
		(duplicate_pad_numbers_are_jumpers no)
		(fp_poly
			(pts
				(xy 0.3048 -0.1016) (xy 0.3048 0.9906) (xy -0.3048 0.9906) (xy -0.3048 -0.1016)
			)
			(stroke
				(width 0)
				(type default)
			)
			(fill no)
			(layer "F.CrtYd")
		)
		(fp_line
			(start 0.3048 -0.1016)
			(end -0.3048 -0.1016)
			(stroke
				(width 0.1)
				(type default)
			)
			(layer "F.Fab")
		)
		(fp_line
			(start -0.3048 -0.1016)
			(end -0.3048 0.9906)
			(stroke
				(width 0.1)
				(type default)
			)
			(layer "F.Fab")
		)
		(fp_line
			(start 0.3048 0.9906)
			(end 0.3048 -0.1016)
			(stroke
				(width 0.1)
				(type default)
			)
			(layer "F.Fab")
		)
		(fp_line
			(start -0.3048 0.9906)
			(end 0.3048 0.9906)
			(stroke
				(width 0.1)
				(type default)
			)
			(layer "F.Fab")
		)
		(pad "1" smd rect
			(at 0 0 90)
			(size 0.508 0.508)
			(layers "F.Cu" "F.Mask" "F.Paste")
			(net "VR_PVCCIO_CPU1_VDD")
		)
		(pad "2" smd rect
			(at 0 0.889 90)
			(size 0.508 0.508)
			(layers "F.Cu" "F.Mask" "F.Paste")
			(net "GND")
		)
		(zone
			(layer "F.Cu")
			(hatch none 0.5)
			(connect_pads
				(clearance 0)
			)
			(min_thickness 0.25)
			(keepout
				(tracks allowed)
				(vias not_allowed)
				(pads allowed)
				(copperpour not_allowed)
				(footprints allowed)
			)
			(placement
				(enabled no)
				(sheetname "")
			)
			(fill
				(thermal_gap 0.5)
				(thermal_bridge_width 0.5)
				(island_removal_mode 0)
			)
			(polygon
				(pts
					(xy 174.1805 -68.58) (xy 174.1805 -69.088) (xy 174.5615 -69.088) (xy 174.5615 -68.58)
				)
			)
		)
		(zone
			(layer "F.Cu")
			(hatch none 0.5)
			(connect_pads
				(clearance 0)
			)
			(min_thickness 0.25)
			(keepout
				(tracks not_allowed)
				(vias allowed)
				(pads allowed)
				(copperpour not_allowed)
				(footprints allowed)
			)
			(placement
				(enabled no)
				(sheetname "")
			)
			(fill
				(thermal_gap 0.5)
				(thermal_bridge_width 0.5)
				(island_removal_mode 0)
			)
			(polygon
				(pts
					(xy 174.5615 -68.58) (xy 174.5615 -69.088) (xy 174.1805 -69.088) (xy 174.1805 -68.58)
				)
			)
		)
	)
	(footprint ""
		(layer "F.Cu")
		(at 421.894 -117.4877 180)
		(property "Reference" "R8B19"
			(at 0 0 180)
			(layer "F.SilkS")
			(hide yes)
			(effects
				(font
					(size 1.27 1.27)
				)
			)
		)
		(property "Value" ""
			(at 0 0 180)
			(layer "F.Fab")
			(effects
				(font
					(size 1.27 1.27)
				)
			)
		)
		(duplicate_pad_numbers_are_jumpers no)
		(fp_poly
			(pts
				(xy -0.2794 -0.1016) (xy 0.2794 -0.1016) (xy 0.2794 0.9906) (xy -0.2794 0.9906)
			)
			(stroke
				(width 0)
				(type default)
			)
			(fill no)
			(layer "F.CrtYd")
		)
		(fp_line
			(start 0.2794 0.9906)
			(end 0.2794 -0.1016)
			(stroke
				(width 0.1)
				(type default)
			)
			(layer "F.Fab")
		)
		(fp_line
			(start 0.2794 -0.1016)
			(end -0.2794 -0.1016)
			(stroke
				(width 0.1)
				(type default)
			)
			(layer "F.Fab")
		)
		(fp_line
			(start -0.2794 0.9906)
			(end 0.2794 0.9906)
			(stroke
				(width 0.1)
				(type default)
			)
			(layer "F.Fab")
		)
		(fp_line
			(start -0.2794 -0.1016)
			(end -0.2794 0.9906)
			(stroke
				(width 0.1)
				(type default)
			)
			(layer "F.Fab")
		)
		(pad "1" smd rect
			(at 0 0 180)
			(size 0.508 0.508)
			(layers "F.Cu" "F.Mask" "F.Paste")
			(net "PVPP_ABC")
		)
		(pad "2" smd rect
			(at 0 0.889 180)
			(size 0.508 0.508)
			(layers "F.Cu" "F.Mask" "F.Paste")
			(net "FM_MODPRST_HFI1_CPU0_LVT2_N")
		)
		(zone
			(layer "F.Cu")
			(hatch none 0.5)
			(connect_pads
				(clearance 0)
			)
			(min_thickness 0.25)
			(keepout
				(tracks not_allowed)
				(vias allowed)
				(pads allowed)
				(copperpour not_allowed)
				(footprints allowed)
			)
			(placement
				(enabled no)
				(sheetname "")
			)
			(fill
				(thermal_gap 0.5)
				(thermal_bridge_width 0.5)
				(island_removal_mode 0)
			)
			(polygon
				(pts
					(xy 422.148 -118.1227) (xy 421.64 -118.1227) (xy 421.64 -117.7417) (xy 422.148 -117.7417)
				)
			)
		)
		(zone
			(layer "F.Cu")
			(hatch none 0.5)
			(connect_pads
				(clearance 0)
			)
			(min_thickness 0.25)
			(keepout
				(tracks allowed)
				(vias not_allowed)
				(pads allowed)
				(copperpour not_allowed)
				(footprints allowed)
			)
			(placement
				(enabled no)
				(sheetname "")
			)
			(fill
				(thermal_gap 0.5)
				(thermal_bridge_width 0.5)
				(island_removal_mode 0)
			)
			(polygon
				(pts
					(xy 422.148 -117.7417) (xy 421.64 -117.7417) (xy 421.64 -118.1227) (xy 422.148 -118.1227)
				)
			)
		)
	)
	(footprint ""
		(layer "F.Cu")
		(at 337.947 -19.7612 90)
		(property "Reference" "R7F27"
			(at 0 0 90)
			(layer "F.SilkS")
			(hide yes)
			(effects
				(font
					(size 1.27 1.27)
				)
			)
		)
		(property "Value" ""
			(at 0 0 90)
			(layer "F.Fab")
			(effects
				(font
					(size 1.27 1.27)
				)
			)
		)
		(duplicate_pad_numbers_are_jumpers no)
		(fp_poly
			(pts
				(xy -0.2794 -0.1016) (xy 0.2794 -0.1016) (xy 0.2794 0.9906) (xy -0.2794 0.9906)
			)
			(stroke
				(width 0)
				(type default)
			)
			(fill no)
			(layer "F.CrtYd")
		)
		(fp_line
			(start 0.2794 -0.1016)
			(end -0.2794 -0.1016)
			(stroke
				(width 0.1)
				(type default)
			)
			(layer "F.Fab")
		)
		(fp_line
			(start -0.2794 -0.1016)
			(end -0.2794 0.9906)
			(stroke
				(width 0.1)
				(type default)
			)
			(layer "F.Fab")
		)
		(fp_line
			(start 0.2794 0.9906)
			(end 0.2794 -0.1016)
			(stroke
				(width 0.1)
				(type default)
			)
			(layer "F.Fab")
		)
		(fp_line
			(start -0.2794 0.9906)
			(end 0.2794 0.9906)
			(stroke
				(width 0.1)
				(type default)
			)
			(layer "F.Fab")
		)
		(pad "1" smd rect
			(at 0 0 90)
			(size 0.508 0.508)
			(layers "F.Cu" "F.Mask" "F.Paste")
			(net "P3V3_STBY")
		)
		(pad "2" smd rect
			(at 0 0.889 90)
			(size 0.508 0.508)
			(layers "F.Cu" "F.Mask" "F.Paste")
			(net "IRQ_PVDDQ_ABC_VRHOT_LVT3_R_N")
		)
		(zone
			(layer "F.Cu")
			(hatch none 0.5)
			(connect_pads
				(clearance 0)
			)
			(min_thickness 0.25)
			(keepout
				(tracks allowed)
				(vias not_allowed)
				(pads allowed)
				(copperpour not_allowed)
				(footprints allowed)
			)
			(placement
				(enabled no)
				(sheetname "")
			)
			(fill
				(thermal_gap 0.5)
				(thermal_bridge_width 0.5)
				(island_removal_mode 0)
			)
			(polygon
				(pts
					(xy 338.201 -19.5072) (xy 338.201 -20.0152) (xy 338.582 -20.0152) (xy 338.582 -19.5072)
				)
			)
		)
		(zone
			(layer "F.Cu")
			(hatch none 0.5)
			(connect_pads
				(clearance 0)
			)
			(min_thickness 0.25)
			(keepout
				(tracks not_allowed)
				(vias allowed)
				(pads allowed)
				(copperpour not_allowed)
				(footprints allowed)
			)
			(placement
				(enabled no)
				(sheetname "")
			)
			(fill
				(thermal_gap 0.5)
				(thermal_bridge_width 0.5)
				(island_removal_mode 0)
			)
			(polygon
				(pts
					(xy 338.582 -19.5072) (xy 338.582 -20.0152) (xy 338.201 -20.0152) (xy 338.201 -19.5072)
				)
			)
		)
	)
	(footprint ""
		(layer "F.Cu")
		(at 411.892242 -47.682404 180)
		(property "Reference" "R25W60"
			(at -0.8382 -0.67818 180)
			(unlocked yes)
			(layer "F.SilkS")
			(effects
				(font
					(size 0.4064 0.254)
					(thickness 0.1524)
				)
				(justify left)
			)
		)
		(property "Value" ""
			(at 0 0 180)
			(layer "F.Fab")
			(effects
				(font
					(size 1.27 1.27)
				)
			)
		)
		(duplicate_pad_numbers_are_jumpers no)
		(fp_poly
			(pts
				(xy -0.2794 -0.1016) (xy 0.2794 -0.1016) (xy 0.2794 0.9906) (xy -0.2794 0.9906)
			)
			(stroke
				(width 0)
				(type default)
			)
			(fill no)
			(layer "F.CrtYd")
		)
		(fp_line
			(start 0.2794 0.9906)
			(end 0.2794 -0.1016)
			(stroke
				(width 0.1)
				(type default)
			)
			(layer "F.Fab")
		)
		(fp_line
			(start 0.2794 -0.1016)
			(end -0.2794 -0.1016)
			(stroke
				(width 0.1)
				(type default)
			)
			(layer "F.Fab")
		)
		(fp_line
			(start -0.2794 0.9906)
			(end 0.2794 0.9906)
			(stroke
				(width 0.1)
				(type default)
			)
			(layer "F.Fab")
		)
		(fp_line
			(start -0.2794 -0.1016)
			(end -0.2794 0.9906)
			(stroke
				(width 0.1)
				(type default)
			)
			(layer "F.Fab")
		)
		(pad "1" smd rect
			(at 0 0 180)
			(size 0.508 0.508)
			(layers "F.Cu" "F.Mask" "F.Paste")
			(net "CLK_100M_BMC_PE_R_DN")
		)
		(pad "2" smd rect
			(at 0 0.889 180)
			(size 0.508 0.508)
			(layers "F.Cu" "F.Mask" "F.Paste")
			(net "GND")
		)
		(zone
			(layer "F.Cu")
			(hatch none 0.5)
			(connect_pads
				(clearance 0)
			)
			(min_thickness 0.25)
			(keepout
				(tracks not_allowed)
				(vias allowed)
				(pads allowed)
				(copperpour not_allowed)
				(footprints allowed)
			)
			(placement
				(enabled no)
				(sheetname "")
			)
			(fill
				(thermal_gap 0.5)
				(thermal_bridge_width 0.5)
				(island_removal_mode 0)
			)
			(polygon
				(pts
					(xy 412.146242 -48.317404) (xy 411.638242 -48.317404) (xy 411.638242 -47.936404) (xy 412.146242 -47.936404)
				)
			)
		)
		(zone
			(layer "F.Cu")
			(hatch none 0.5)
			(connect_pads
				(clearance 0)
			)
			(min_thickness 0.25)
			(keepout
				(tracks allowed)
				(vias not_allowed)
				(pads allowed)
				(copperpour not_allowed)
				(footprints allowed)
			)
			(placement
				(enabled no)
				(sheetname "")
			)
			(fill
				(thermal_gap 0.5)
				(thermal_bridge_width 0.5)
				(island_removal_mode 0)
			)
			(polygon
				(pts
					(xy 412.146242 -47.936404) (xy 411.638242 -47.936404) (xy 411.638242 -48.317404) (xy 412.146242 -48.317404)
				)
			)
		)
	)
	(footprint ""
		(layer "F.Cu")
		(at 487.2228 -138.4554 180)
		(property "Reference" "C6W10"
			(at -0.8382 -0.67818 180)
			(unlocked yes)
			(layer "F.SilkS")
			(effects
				(font
					(size 0.4064 0.254)
					(thickness 0.1524)
				)
				(justify left)
			)
		)
		(property "Value" ""
			(at 0 0 180)
			(layer "F.Fab")
			(effects
				(font
					(size 1.27 1.27)
				)
			)
		)
		(duplicate_pad_numbers_are_jumpers no)
		(fp_poly
			(pts
				(xy 0.3048 -0.1016) (xy 0.3048 0.9906) (xy -0.3048 0.9906) (xy -0.3048 -0.1016)
			)
			(stroke
				(width 0)
				(type default)
			)
			(fill no)
			(layer "F.CrtYd")
		)
		(fp_line
			(start 0.3048 0.9906)
			(end 0.3048 -0.1016)
			(stroke
				(width 0.1)
				(type default)
			)
			(layer "F.Fab")
		)
		(fp_line
			(start 0.3048 -0.1016)
			(end -0.3048 -0.1016)
			(stroke
				(width 0.1)
				(type default)
			)
			(layer "F.Fab")
		)
		(fp_line
			(start -0.3048 0.9906)
			(end 0.3048 0.9906)
			(stroke
				(width 0.1)
				(type default)
			)
			(layer "F.Fab")
		)
		(fp_line
			(start -0.3048 -0.1016)
			(end -0.3048 0.9906)
			(stroke
				(width 0.1)
				(type default)
			)
			(layer "F.Fab")
		)
		(pad "1" smd rect
			(at 0 0 180)
			(size 0.508 0.508)
			(layers "F.Cu" "F.Mask" "F.Paste")
			(net "P3V3_STBY")
		)
		(pad "2" smd rect
			(at 0 0.889 180)
			(size 0.508 0.508)
			(layers "F.Cu" "F.Mask" "F.Paste")
			(net "GND")
		)
		(zone
			(layer "F.Cu")
			(hatch none 0.5)
			(connect_pads
				(clearance 0)
			)
			(min_thickness 0.25)
			(keepout
				(tracks not_allowed)
				(vias allowed)
				(pads allowed)
				(copperpour not_allowed)
				(footprints allowed)
			)
			(placement
				(enabled no)
				(sheetname "")
			)
			(fill
				(thermal_gap 0.5)
				(thermal_bridge_width 0.5)
				(island_removal_mode 0)
			)
			(polygon
				(pts
					(xy 487.4768 -139.0904) (xy 486.9688 -139.0904) (xy 486.9688 -138.7094) (xy 487.4768 -138.7094)
				)
			)
		)
		(zone
			(layer "F.Cu")
			(hatch none 0.5)
			(connect_pads
				(clearance 0)
			)
			(min_thickness 0.25)
			(keepout
				(tracks allowed)
				(vias not_allowed)
				(pads allowed)
				(copperpour not_allowed)
				(footprints allowed)
			)
			(placement
				(enabled no)
				(sheetname "")
			)
			(fill
				(thermal_gap 0.5)
				(thermal_bridge_width 0.5)
				(island_removal_mode 0)
			)
			(polygon
				(pts
					(xy 487.4768 -138.7094) (xy 486.9688 -138.7094) (xy 486.9688 -139.0904) (xy 487.4768 -139.0904)
				)
			)
		)
	)
	(footprint ""
		(layer "F.Cu")
		(at 162.6362 -66.675 -90)
		(property "Reference" "R3D28"
			(at 0 0 270)
			(layer "F.SilkS")
			(hide yes)
			(effects
				(font
					(size 1.27 1.27)
				)
			)
		)
		(property "Value" ""
			(at 0 0 270)
			(layer "F.Fab")
			(effects
				(font
					(size 1.27 1.27)
				)
			)
		)
		(duplicate_pad_numbers_are_jumpers no)
		(fp_poly
			(pts
				(xy -0.2794 -0.1016) (xy 0.2794 -0.1016) (xy 0.2794 0.9906) (xy -0.2794 0.9906)
			)
			(stroke
				(width 0)
				(type default)
			)
			(fill no)
			(layer "F.CrtYd")
		)
		(fp_line
			(start -0.2794 0.9906)
			(end 0.2794 0.9906)
			(stroke
				(width 0.1)
				(type default)
			)
			(layer "F.Fab")
		)
		(fp_line
			(start 0.2794 0.9906)
			(end 0.2794 -0.1016)
			(stroke
				(width 0.1)
				(type default)
			)
			(layer "F.Fab")
		)
		(fp_line
			(start -0.2794 -0.1016)
			(end -0.2794 0.9906)
			(stroke
				(width 0.1)
				(type default)
			)
			(layer "F.Fab")
		)
		(fp_line
			(start 0.2794 -0.1016)
			(end -0.2794 -0.1016)
			(stroke
				(width 0.1)
				(type default)
			)
			(layer "F.Fab")
		)
		(pad "1" smd rect
			(at 0 0 270)
			(size 0.508 0.508)
			(layers "F.Cu" "F.Mask" "F.Paste")
			(net "VSENSE_PVCCIO_CPU1_AVSN")
		)
		(pad "2" smd rect
			(at 0 0.889 270)
			(size 0.508 0.508)
			(layers "F.Cu" "F.Mask" "F.Paste")
			(net "GND")
		)
		(zone
			(layer "F.Cu")
			(hatch none 0.5)
			(connect_pads
				(clearance 0)
			)
			(min_thickness 0.25)
			(keepout
				(tracks not_allowed)
				(vias allowed)
				(pads allowed)
				(copperpour not_allowed)
				(footprints allowed)
			)
			(placement
				(enabled no)
				(sheetname "")
			)
			(fill
				(thermal_gap 0.5)
				(thermal_bridge_width 0.5)
				(island_removal_mode 0)
			)
			(polygon
				(pts
					(xy 162.0012 -66.929) (xy 162.0012 -66.421) (xy 162.3822 -66.421) (xy 162.3822 -66.929)
				)
			)
		)
		(zone
			(layer "F.Cu")
			(hatch none 0.5)
			(connect_pads
				(clearance 0)
			)
			(min_thickness 0.25)
			(keepout
				(tracks allowed)
				(vias not_allowed)
				(pads allowed)
				(copperpour not_allowed)
				(footprints allowed)
			)
			(placement
				(enabled no)
				(sheetname "")
			)
			(fill
				(thermal_gap 0.5)
				(thermal_bridge_width 0.5)
				(island_removal_mode 0)
			)
			(polygon
				(pts
					(xy 162.3822 -66.929) (xy 162.3822 -66.421) (xy 162.0012 -66.421) (xy 162.0012 -66.929)
				)
			)
		)
	)
)
